(kicad_pcb
	(version 20260206)
	(generator "pcbnew")
	(generator_version "10.0")
	(general
		(thickness 1.6)
		(legacy_teardrops no)
	)
	(paper "A4")
	(title_block
		(title "Bryce Canyon_R.DPB_16317-1_OCP.brd")
		(comment 1 "Bryce Canyon / footprints 383-385 of 2099")
	)
	(layers
		(0 "F.Cu" signal "TOP")
		(4 "In1.Cu" signal "L2GND")
		(6 "In2.Cu" signal "L3")
		(8 "In3.Cu" signal "L4VCC")
		(10 "In4.Cu" signal "L5VCC")
		(12 "In5.Cu" signal "L6")
		(14 "In6.Cu" signal "L7GND")
		(2 "B.Cu" signal "BOTTOM")
		(9 "F.Adhes" user "F.Adhesive")
		(11 "B.Adhes" user "B.Adhesive")
		(13 "F.Paste" user "Package Geometry/Pastemask Top")
		(15 "B.Paste" user "Package Geometry/Pastemask Bottom")
		(5 "F.SilkS" user "Ref Des/Silkscreen Top")
		(7 "B.SilkS" user "Ref Des/Silkscreen Bottom")
		(1 "F.Mask" user "Board Geometry/Soldermask Top")
		(3 "B.Mask" user "Board Geometry/Soldermask Bottom")
		(17 "Dwgs.User" user "User.Drawings")
		(19 "Cmts.User" user "User.Comments")
		(21 "Eco1.User" user "User.Eco1")
		(23 "Eco2.User" user "User.Eco2")
		(25 "Edge.Cuts" user "Board Geometry/Outline")
		(27 "Margin" user)
		(31 "F.CrtYd" user "Package Geometry/Place Bound Top")
		(29 "B.CrtYd" user "Package Geometry/Place Bound Bottom")
		(35 "F.Fab" user "Ref Des/Assembly Top")
		(33 "B.Fab" user "Ref Des/Assembly Bottom")
	)
	(footprint ""
		(layer "F.Cu")
		(at 154.399996 -143.91005 -90)
		(property "Reference" "HDDSAS16"
			(at 0 0 270)
			(layer "F.SilkS")
			(hide yes)
			(effects
				(font
					(size 1.27 1.27)
				)
			)
		)
		(property "Value" "SKT-SAS15P-14P-45-GP"
			(at -20.7645 -8.9789 270)
			(unlocked yes)
			(layer "F.Fab")
			(hide yes)
			(effects
				(font
					(size 1.016 1.016)
					(thickness 0.1524)
				)
			)
		)
		(property "Device Type" "10120818-001C-TRLF"
			(at -20.7645 -10.5029 270)
			(unlocked yes)
			(layer "F.Fab")
			(hide yes)
			(effects
				(font
					(size 1.016 1.016)
					(thickness 0.1524)
				)
			)
		)
		(duplicate_pad_numbers_are_jumpers no)
		(fp_line
			(start 1.651 4.2926)
			(end 1.651 3.0099)
			(stroke
				(width 0.1524)
				(type default)
			)
			(layer "F.SilkS")
		)
		(fp_line
			(start 8.509 4.2926)
			(end 1.651 4.2926)
			(stroke
				(width 0.1524)
				(type default)
			)
			(layer "F.SilkS")
		)
		(fp_line
			(start -23.4188 3.0099)
			(end -23.4188 -3.2512)
			(stroke
				(width 0.1524)
				(type default)
			)
			(layer "F.SilkS")
		)
		(fp_line
			(start 1.651 3.0099)
			(end -23.4188 3.0099)
			(stroke
				(width 0.1524)
				(type default)
			)
			(layer "F.SilkS")
		)
		(fp_line
			(start 8.509 3.0099)
			(end 8.509 4.2926)
			(stroke
				(width 0.1524)
				(type default)
			)
			(layer "F.SilkS")
		)
		(fp_line
			(start 23.4188 3.0099)
			(end 8.509 3.0099)
			(stroke
				(width 0.1524)
				(type default)
			)
			(layer "F.SilkS")
		)
		(fp_line
			(start -23.4188 -3.2512)
			(end 23.4188 -3.2512)
			(stroke
				(width 0.1524)
				(type default)
			)
			(layer "F.SilkS")
		)
		(fp_line
			(start 23.4188 -3.2512)
			(end 23.4188 3.0099)
			(stroke
				(width 0.1524)
				(type default)
			)
			(layer "F.SilkS")
		)
		(fp_line
			(start 15.5067 -3.3401)
			(end 16.2687 -3.3401)
			(stroke
				(width 0.3302)
				(type default)
			)
			(layer "F.SilkS")
		)
		(fp_poly
			(pts
				(xy 15.868904 -3.230372) (xy 16.503904 -3.865372) (xy 15.233904 -3.865372)
			)
			(stroke
				(width 0)
				(type default)
			)
			(fill yes)
			(layer "F.SilkS")
		)
		(fp_poly
			(pts
				(xy -22.8727 -2.7559) (xy 22.8727 -2.7559) (xy 22.8727 2.7559) (xy 8.255 2.7559) (xy 8.255 3.5179)
				(xy 1.905 3.5179) (xy 1.905 2.7559) (xy -22.8727 2.7559)
			)
			(stroke
				(width 0)
				(type default)
			)
			(fill no)
			(layer "F.CrtYd")
		)
		(fp_poly
			(pts
				(xy 1.397 4.5466) (xy 1.397 3.2639) (xy -23.6728 3.2639) (xy -23.6728 -3.5052) (xy 23.6728 -3.5052)
				(xy 23.6728 -0.00635) (xy 22.8727 -0.00635) (xy 22.8727 -2.7559) (xy -22.8727 -2.7559) (xy -22.8727 2.7559)
				(xy 1.905 2.7559) (xy 1.905 3.5179) (xy 8.255 3.5179) (xy 8.255 2.7559) (xy 22.8727 2.7559) (xy 22.8727 0.00635)
				(xy 23.6728 0.00635) (xy 23.6728 3.2639) (xy 8.763 3.2639) (xy 8.763 4.5466)
			)
			(stroke
				(width 0)
				(type default)
			)
			(fill no)
			(layer "F.CrtYd")
		)
		(fp_poly
			(pts
				(xy 1.397 4.5466) (xy 1.397 3.2639) (xy -23.6728 3.2639) (xy -23.6728 -3.5052) (xy 23.6728 -3.5052)
				(xy 23.6728 3.2639) (xy 8.763 3.2639) (xy 8.763 4.5466)
			)
			(stroke
				(width 0)
				(type default)
			)
			(fill no)
			(layer "F.Fab")
		)
		(pad "" np_thru_hole circle
			(at -18.874994 0 270)
			(size 0.254 0.254)
			(drill 1.3462)
			(layers "*.Cu" "*.Mask")
			(clearance 0.9017)
			(thermal_gap 0.9017)
		)
		(pad "" np_thru_hole circle
			(at 18.874994 0 270)
			(size 0.254 0.254)
			(drill 0.9398)
			(layers "*.Cu" "*.Mask")
			(clearance 0.6985)
			(thermal_gap 0.6985)
		)
		(pad "G1" smd rect
			(at 21.874988 0 270)
			(size 2.5908 2.5908)
			(layers "F.Cu" "F.Mask" "F.Paste")
			(net "GND")
		)
		(pad "G2" smd rect
			(at -21.874988 0 270)
			(size 2.5908 2.5908)
			(layers "F.Cu" "F.Mask" "F.Paste")
			(net "GND")
		)
		(pad "P1" smd rect
			(at 1.905 -1.82499 270)
			(size 0.6096 2.3622)
			(layers "F.Cu" "F.Mask" "F.Paste")
			(net "Net_1724")
		)
		(pad "P2" smd rect
			(at 0.635 -1.82499 270)
			(size 0.6096 2.3622)
			(layers "F.Cu" "F.Mask" "F.Paste")
			(net "Net_1725")
		)
		(pad "P3" smd rect
			(at -0.635 -1.82499 270)
			(size 0.6096 2.3622)
			(layers "F.Cu" "F.Mask" "F.Paste")
			(net "Net_1726")
		)
		(pad "P4" smd rect
			(at -1.905 -1.82499 270)
			(size 0.6096 2.3622)
			(layers "F.Cu" "F.Mask" "F.Paste")
			(net "GND")
		)
		(pad "P5" smd rect
			(at -3.175 -1.82499 270)
			(size 0.6096 2.3622)
			(layers "F.Cu" "F.Mask" "F.Paste")
			(net "HDD_PRSNT_16")
		)
		(pad "P6" smd rect
			(at -4.445 -1.82499 270)
			(size 0.6096 2.3622)
			(layers "F.Cu" "F.Mask" "F.Paste")
			(net "GND")
		)
		(pad "P7" smd rect
			(at -5.715 -1.82499 270)
			(size 0.6096 2.3622)
			(layers "F.Cu" "F.Mask" "F.Paste")
			(net "5V_PRE_16")
		)
		(pad "P8" smd rect
			(at -6.985 -1.82499 270)
			(size 0.6096 2.3622)
			(layers "F.Cu" "F.Mask" "F.Paste")
			(net "P5V_HDD16")
		)
		(pad "P9" smd rect
			(at -8.255 -1.82499 270)
			(size 0.6096 2.3622)
			(layers "F.Cu" "F.Mask" "F.Paste")
			(net "P5V_HDD16")
		)
		(pad "P10" smd rect
			(at -9.525 -1.82499 270)
			(size 0.6096 2.3622)
			(layers "F.Cu" "F.Mask" "F.Paste")
			(net "GND")
		)
		(pad "P11" smd rect
			(at -10.795 -1.82499 270)
			(size 0.6096 2.3622)
			(layers "F.Cu" "F.Mask" "F.Paste")
			(net "ACT_HDD_16")
		)
		(pad "P12" smd rect
			(at -12.065 -1.82499 270)
			(size 0.6096 2.3622)
			(layers "F.Cu" "F.Mask" "F.Paste")
			(net "GND")
		)
		(pad "P13" smd rect
			(at -13.335 -1.82499 270)
			(size 0.6096 2.3622)
			(layers "F.Cu" "F.Mask" "F.Paste")
			(net "12V_PRE_16")
		)
		(pad "P14" smd rect
			(at -14.605 -1.82499 270)
			(size 0.6096 2.3622)
			(layers "F.Cu" "F.Mask" "F.Paste")
			(net "P12V_HDD16")
		)
		(pad "P15" smd rect
			(at -15.875 -1.82499 270)
			(size 0.6096 2.3622)
			(layers "F.Cu" "F.Mask" "F.Paste")
			(net "P12V_HDD16")
		)
		(pad "S1" smd rect
			(at 15.875 -1.82499 270)
			(size 0.6096 2.3622)
			(layers "F.Cu" "F.Mask" "F.Paste")
			(net "GND")
		)
		(pad "S2" smd rect
			(at 14.605 -1.82499 270)
			(size 0.6096 2.3622)
			(layers "F.Cu" "F.Mask" "F.Paste")
			(net "SAS_HDD_RX_P16")
		)
		(pad "S3" smd rect
			(at 13.335 -1.82499 270)
			(size 0.6096 2.3622)
			(layers "F.Cu" "F.Mask" "F.Paste")
			(net "SAS_HDD_RX_N16")
		)
		(pad "S4" smd rect
			(at 12.065 -1.82499 270)
			(size 0.6096 2.3622)
			(layers "F.Cu" "F.Mask" "F.Paste")
			(net "GND")
		)
		(pad "S5" smd rect
			(at 10.795 -1.82499 270)
			(size 0.6096 2.3622)
			(layers "F.Cu" "F.Mask" "F.Paste")
			(net "PHY_DRV_B_TO_SCC_B_16_DN")
		)
		(pad "S6" smd rect
			(at 9.525 -1.82499 270)
			(size 0.6096 2.3622)
			(layers "F.Cu" "F.Mask" "F.Paste")
			(net "PHY_DRV_B_TO_SCC_B_16_DP")
		)
		(pad "S7" smd rect
			(at 8.255 -1.82499 270)
			(size 0.6096 2.3622)
			(layers "F.Cu" "F.Mask" "F.Paste")
			(net "GND")
		)
		(pad "S8" smd rect
			(at 7.480046 2.845054 270)
			(size 0.508 2.3622)
			(layers "F.Cu" "F.Mask" "F.Paste")
			(net "GND")
		)
		(pad "S9" smd rect
			(at 6.679946 2.845054 270)
			(size 0.508 2.3622)
			(layers "F.Cu" "F.Mask" "F.Paste")
			(net "Net_439")
		)
		(pad "S10" smd rect
			(at 5.8801 2.845054 270)
			(size 0.508 2.3622)
			(layers "F.Cu" "F.Mask" "F.Paste")
			(net "Net_331")
		)
		(pad "S11" smd rect
			(at 5.08 2.845054 270)
			(size 0.508 2.3622)
			(layers "F.Cu" "F.Mask" "F.Paste")
			(net "GND")
		)
		(pad "S12" smd rect
			(at 4.2799 2.845054 270)
			(size 0.508 2.3622)
			(layers "F.Cu" "F.Mask" "F.Paste")
			(net "Net_367")
		)
		(pad "S13" smd rect
			(at 3.480054 2.845054 270)
			(size 0.508 2.3622)
			(layers "F.Cu" "F.Mask" "F.Paste")
			(net "Net_403")
		)
		(pad "S14" smd rect
			(at 2.679954 2.845054 270)
			(size 0.508 2.3622)
			(layers "F.Cu" "F.Mask" "F.Paste")
			(net "GND")
		)
		(zone
			(layer "F.Cu")
			(hatch none 0.5)
			(connect_pads
				(clearance 0)
			)
			(min_thickness 0.25)
			(keepout
				(tracks not_allowed)
				(vias allowed)
				(pads allowed)
				(copperpour not_allowed)
				(footprints allowed)
			)
			(placement
				(enabled no)
				(sheetname "")
			)
			(fill
				(thermal_gap 0.5)
				(thermal_bridge_width 0.5)
				(island_removal_mode 0)
			)
			(polygon
				(pts
					(xy 158.057596 -160.64865) (xy 150.983696 -160.64865) (xy 150.983696 -167.58285) (xy 152.088596 -167.58285)
					(xy 152.088596 -163.46805) (xy 156.711396 -163.46805) (xy 156.711396 -167.58285) (xy 158.057596 -167.58285)
				)
			)
		)
		(zone
			(layer "F.Cu")
			(hatch none 0.5)
			(connect_pads
				(clearance 0)
			)
			(min_thickness 0.25)
			(keepout
				(tracks allowed)
				(vias not_allowed)
				(pads allowed)
				(copperpour not_allowed)
				(footprints allowed)
			)
			(placement
				(enabled no)
				(sheetname "")
			)
			(fill
				(thermal_gap 0.5)
				(thermal_bridge_width 0.5)
				(island_removal_mode 0)
			)
			(polygon
				(pts
					(xy 158.057596 -160.64865) (xy 150.983696 -160.64865) (xy 150.983696 -167.58285) (xy 152.088596 -167.58285)
					(xy 152.088596 -163.46805) (xy 156.711396 -163.46805) (xy 156.711396 -167.58285) (xy 158.057596 -167.58285)
				)
			)
		)
		(zone
			(layer "F.Cu")
			(hatch none 0.5)
			(connect_pads
				(clearance 0)
			)
			(min_thickness 0.25)
			(keepout
				(tracks allowed)
				(vias not_allowed)
				(pads allowed)
				(copperpour not_allowed)
				(footprints allowed)
			)
			(placement
				(enabled no)
				(sheetname "")
			)
			(fill
				(thermal_gap 0.5)
				(thermal_bridge_width 0.5)
				(island_removal_mode 0)
			)
			(polygon
				(pts
					(xy 158.057596 -127.17145) (xy 150.983696 -127.17145) (xy 150.983696 -120.23725) (xy 152.088596 -120.23725)
					(xy 152.088596 -124.35205) (xy 156.711396 -124.35205) (xy 156.711396 -120.23725) (xy 158.057596 -120.23725)
				)
			)
		)
		(zone
			(layer "F.Cu")
			(hatch none 0.5)
			(connect_pads
				(clearance 0)
			)
			(min_thickness 0.25)
			(keepout
				(tracks not_allowed)
				(vias allowed)
				(pads allowed)
				(copperpour not_allowed)
				(footprints allowed)
			)
			(placement
				(enabled no)
				(sheetname "")
			)
			(fill
				(thermal_gap 0.5)
				(thermal_bridge_width 0.5)
				(island_removal_mode 0)
			)
			(polygon
				(pts
					(xy 158.057596 -127.17145) (xy 150.983696 -127.17145) (xy 150.983696 -120.23725) (xy 152.088596 -120.23725)
					(xy 152.088596 -124.35205) (xy 156.711396 -124.35205) (xy 156.711396 -120.23725) (xy 158.057596 -120.23725)
				)
			)
		)
		(zone
			(layers "F.Cu" "B.Cu" "In1.Cu" "In2.Cu" "In3.Cu" "In4.Cu" "In5.Cu" "In6.Cu")
			(hatch none 0.5)
			(connect_pads
				(clearance 0)
			)
			(min_thickness 0.25)
			(keepout
				(tracks not_allowed)
				(vias allowed)
				(pads allowed)
				(copperpour not_allowed)
				(footprints allowed)
			)
			(placement
				(enabled no)
				(sheetname "")
			)
			(fill
				(thermal_gap 0.5)
				(thermal_bridge_width 0.5)
				(island_removal_mode 0)
			)
			(polygon
				(pts
					(arc
						(start 155.174696 -125.035056)
						(mid 153.625296 -125.035056)
						(end 155.174696 -125.035056)
					)
				)
			)
		)
		(zone
			(layers "F.Cu" "B.Cu" "In1.Cu" "In2.Cu" "In3.Cu" "In4.Cu" "In5.Cu" "In6.Cu")
			(hatch none 0.5)
			(connect_pads
				(clearance 0)
			)
			(min_thickness 0.25)
			(keepout
				(tracks not_allowed)
				(vias allowed)
				(pads allowed)
				(copperpour not_allowed)
				(footprints allowed)
			)
			(placement
				(enabled no)
				(sheetname "")
			)
			(fill
				(thermal_gap 0.5)
				(thermal_bridge_width 0.5)
				(island_removal_mode 0)
			)
			(polygon
				(pts
					(arc
						(start 155.377896 -162.785044)
						(mid 153.422096 -162.785044)
						(end 155.377896 -162.785044)
					)
				)
			)
		)
	)
	(footprint ""
		(layer "F.Cu")
		(at 459.260194 -373.634 -90)
		(property "Reference" "R1308"
			(at 0 0 270)
			(layer "F.SilkS")
			(hide yes)
			(effects
				(font
					(size 1.27 1.27)
				)
			)
		)
		(property "Value" "4K7R2F-GP"
			(at 0.064008 -3.993896 270)
			(unlocked yes)
			(layer "F.Fab")
			(hide yes)
			(effects
				(font
					(size 1.016 1.016)
					(thickness 0.1524)
				)
			)
		)
		(property "Device Type" "R402H16"
			(at 0.064008 -5.517896 270)
			(unlocked yes)
			(layer "F.Fab")
			(hide yes)
			(effects
				(font
					(size 1.016 1.016)
					(thickness 0.1524)
				)
			)
		)
		(duplicate_pad_numbers_are_jumpers no)
		(fp_line
			(start -0.508 -0.9398)
			(end -0.508 0.9398)
			(stroke
				(width 0.1524)
				(type default)
			)
			(layer "F.SilkS")
		)
		(fp_line
			(start 0.508 -0.9398)
			(end -0.508 -0.9398)
			(stroke
				(width 0.1524)
				(type default)
			)
			(layer "F.SilkS")
		)
		(fp_rect
			(start -0.508 0.9398)
			(end 0.508 -0.9398)
			(stroke
				(width 0)
				(type default)
			)
			(fill no)
			(layer "F.CrtYd")
		)
		(fp_rect
			(start -0.508 0.9398)
			(end 0.508 -0.9398)
			(stroke
				(width 0)
				(type default)
			)
			(fill no)
			(layer "F.Fab")
		)
		(pad "1" smd custom
			(at 0 -0.4445 270)
			(size 0.1397 0.1397)
			(layers "F.Cu" "F.Mask" "F.Paste")
			(net "FAN_YELLOW_LED3")
			(options
				(clearance outline)
				(anchor circle)
			)
			(primitives
				(gr_poly
					(pts
						(arc
							(start -0.1778 -0.2794)
							(mid -0.249642 -0.249642)
							(end -0.2794 -0.1778)
						)
						(arc
							(start -0.2794 0.1778)
							(mid -0.249642 0.249642)
							(end -0.1778 0.2794)
						)
						(arc
							(start 0.1778 0.2794)
							(mid 0.249642 0.249642)
							(end 0.2794 0.1778)
						)
						(arc
							(start 0.2794 -0.1778)
							(mid 0.249642 -0.249642)
							(end 0.1778 -0.2794)
						)
					)
					(width 0)
					(fill yes)
				)
			)
		)
		(pad "2" smd custom
			(at 0 0.4445 270)
			(size 0.1397 0.1397)
			(layers "F.Cu" "F.Mask" "F.Paste")
			(net "FAN_LED3_D2")
			(options
				(clearance outline)
				(anchor circle)
			)
			(primitives
				(gr_poly
					(pts
						(arc
							(start -0.1778 -0.2794)
							(mid -0.249642 -0.249642)
							(end -0.2794 -0.1778)
						)
						(arc
							(start -0.2794 0.1778)
							(mid -0.249642 0.249642)
							(end -0.1778 0.2794)
						)
						(arc
							(start 0.1778 0.2794)
							(mid 0.249642 0.249642)
							(end 0.2794 0.1778)
						)
						(arc
							(start 0.2794 -0.1778)
							(mid 0.249642 -0.249642)
							(end 0.1778 -0.2794)
						)
					)
					(width 0)
					(fill yes)
				)
			)
		)
	)
	(footprint ""
		(layer "F.Cu")
		(at 80.900016 -180.399944)
		(property "Reference" "LED3"
			(at 0 0 0)
			(layer "F.SilkS")
			(hide yes)
			(effects
				(font
					(size 1.27 1.27)
				)
			)
		)
		(property "Value" "LED-BY-19-GP"
			(at -2.132076 1.414018 0)
			(unlocked yes)
			(layer "F.Fab")
			(hide yes)
			(effects
				(font
					(size 1.016 1.016)
					(thickness 0.1524)
				)
			)
		)
		(property "Device Type" "LED-1615-4PH26"
			(at -2.132076 -0.109982 0)
			(unlocked yes)
			(layer "F.Fab")
			(hide yes)
			(effects
				(font
					(size 1.016 1.016)
					(thickness 0.1524)
				)
			)
		)
		(duplicate_pad_numbers_are_jumpers no)
		(fp_line
			(start -1.2954 0.254)
			(end -1.2954 1.6002)
			(stroke
				(width 0.508)
				(type default)
			)
			(layer "F.SilkS")
		)
		(fp_line
			(start -1.2954 1.6002)
			(end 1.2954 1.6002)
			(stroke
				(width 0.508)
				(type default)
			)
			(layer "F.SilkS")
		)
		(fp_line
			(start -1.1176 -1.4224)
			(end 1.1176 -1.4224)
			(stroke
				(width 0.1524)
				(type default)
			)
			(layer "F.SilkS")
		)
		(fp_line
			(start -1.1176 1.4224)
			(end -1.1176 -1.4224)
			(stroke
				(width 0.1524)
				(type default)
			)
			(layer "F.SilkS")
		)
		(fp_line
			(start 1.1176 -1.4224)
			(end 1.1176 1.4224)
			(stroke
				(width 0.1524)
				(type default)
			)
			(layer "F.SilkS")
		)
		(fp_line
			(start 1.1176 1.4224)
			(end -1.1176 1.4224)
			(stroke
				(width 0.1524)
				(type default)
			)
			(layer "F.SilkS")
		)
		(fp_line
			(start 1.2954 1.6002)
			(end 1.2954 0.254)
			(stroke
				(width 0.508)
				(type default)
			)
			(layer "F.SilkS")
		)
		(fp_rect
			(start -0.7493 0.8001)
			(end 0.7493 -0.8001)
			(stroke
				(width 0)
				(type default)
			)
			(fill no)
			(layer "F.CrtYd")
		)
		(fp_poly
			(pts
				(xy -1.3716 1.6764) (xy -1.3716 -1.6764) (xy 1.3716 -1.6764) (xy 1.3716 0.0635) (xy 0.7493 0.0635)
				(xy 0.7493 -0.8001) (xy -0.7493 -0.8001) (xy -0.7493 0.8001) (xy 0.7493 0.8001) (xy 0.7493 0.0762)
				(xy 1.3716 0.0762) (xy 1.3716 1.6764)
			)
			(stroke
				(width 0)
				(type default)
			)
			(fill no)
			(layer "F.CrtYd")
		)
		(fp_rect
			(start -1.3716 1.6764)
			(end 1.3716 -1.6764)
			(stroke
				(width 0)
				(type default)
			)
			(fill no)
			(layer "F.Fab")
		)
		(pad "1" smd rect
			(at 0.50038 -0.73025)
			(size 0.7112 0.8636)
			(layers "F.Cu" "F.Mask" "F.Paste")
			(net "DRV_ACT_2")
		)
		(pad "2" smd rect
			(at -0.50038 -0.73025)
			(size 0.7112 0.8636)
			(layers "F.Cu" "F.Mask" "F.Paste")
			(net "FLT_HDD2")
		)
		(pad "3" smd rect
			(at 0.50038 0.73025)
			(size 0.7112 0.8636)
			(layers "F.Cu" "F.Mask" "F.Paste")
			(net "DRV_ACT_2_N")
		)
		(pad "4" smd rect
			(at -0.50038 0.73025)
			(size 0.7112 0.8636)
			(layers "F.Cu" "F.Mask" "F.Paste")
			(net "FLT_HDD2_N")
		)
	)
)
